# T6G (Grand Teton) — schematic netlist excerpt (pin names and nets, part order shuffled) for the footprints in the layout excerpt that follows; sources: Cadence DE-HDL packaged netlist, KiCad conversion of 04192023_DAF0TMB3IC0_F0TG_MB_C_brd_V02_OCP.brd

C9104  Q_CAP_DIFFBUS  DIFF BUS_0.22UF 6.3V 20% X6S  pkg C0201  page 67 : \1\ = P3E_CPU1_P4_TX_C_DP<0> ; \2\ = P3E_CPU1_P4_TX_DP<0>
PC441_2  Q_CAP  1UF 25V 10% X6S  pkg C0402  page 222 : A = SW_P12V_AUX_PVDDIO_P1_FLT ; B = GND

(kicad_pcb
	(version 20260206)
	(generator "pcbnew")
	(generator_version "10.0")
	(general
		(thickness 1.6)
		(legacy_teardrops no)
	)
	(paper "A4")
	(title_block
		(title "04192023_DAF0TMB3IC0_F0TG_MB_C_brd_V02_OCP.brd")
		(comment 1 "Grand Teton / footprints 825-826 of 8354")
	)
	(layers
		(0 "F.Cu" signal "TOP")
		(4 "In1.Cu" signal "GND")
		(6 "In2.Cu" signal "IN1")
		(8 "In3.Cu" signal "GND1")
		(10 "In4.Cu" signal "IN2")
		(12 "In5.Cu" signal "GND2")
		(14 "In6.Cu" signal "IN3")
		(16 "In7.Cu" signal "GND3")
		(18 "In8.Cu" signal "VCC")
		(20 "In9.Cu" signal "VCC1")
		(22 "In10.Cu" signal "GND4")
		(24 "In11.Cu" signal "IN4")
		(26 "In12.Cu" signal "GND5")
		(28 "In13.Cu" signal "IN5")
		(30 "In14.Cu" signal "GND6")
		(32 "In15.Cu" signal "IN6")
		(34 "In16.Cu" signal "GND7")
		(2 "B.Cu" signal "BOTTOM")
		(9 "F.Adhes" user "F.Adhesive")
		(11 "B.Adhes" user "B.Adhesive")
		(13 "F.Paste" user "Package Geometry/Pastemask Top")
		(15 "B.Paste" user "Package Geometry/Pastemask Bottom")
		(5 "F.SilkS" user "Ref Des/Silkscreen Top")
		(7 "B.SilkS" user "Ref Des/Silkscreen Bottom")
		(1 "F.Mask" user "Board Geometry/Soldermask Top")
		(3 "B.Mask" user "Board Geometry/Soldermask Bottom")
		(17 "Dwgs.User" user "User.Drawings")
		(19 "Cmts.User" user "User.Comments")
		(21 "Eco1.User" user "User.Eco1")
		(23 "Eco2.User" user "User.Eco2")
		(25 "Edge.Cuts" user "Board Geometry/Outline")
		(27 "Margin" user)
		(31 "F.CrtYd" user "Package Geometry/Place Bound Top")
		(29 "B.CrtYd" user "Package Geometry/Place Bound Bottom")
		(35 "F.Fab" user "Ref Des/Assembly Top")
		(33 "B.Fab" user "Ref Des/Assembly Bottom")
	)
	(footprint ""
		(layer "F.Cu")
		(at 180.528468 -44.091098)
		(property "Reference" "C9104"
			(at 0 0 0)
			(layer "F.SilkS")
			(hide yes)
			(effects
				(font
					(size 1.27 1.27)
				)
			)
		)
		(property "Value" ""
			(at 0 0 0)
			(layer "F.Fab")
			(effects
				(font
					(size 1.27 1.27)
				)
			)
		)
		(duplicate_pad_numbers_are_jumpers no)
		(fp_line
			(start -0.299974 -0.150114)
			(end 0.299974 -0.150114)
			(stroke
				(width 0.1)
				(type default)
			)
			(layer "F.Fab")
		)
		(fp_line
			(start -0.299974 0.150114)
			(end -0.299974 -0.150114)
			(stroke
				(width 0.1)
				(type default)
			)
			(layer "F.Fab")
		)
		(fp_line
			(start 0.299974 -0.150114)
			(end 0.299974 0.150114)
			(stroke
				(width 0.1)
				(type default)
			)
			(layer "F.Fab")
		)
		(fp_line
			(start 0.299974 0.150114)
			(end -0.299974 0.150114)
			(stroke
				(width 0.1)
				(type default)
			)
			(layer "F.Fab")
		)
		(pad "1" smd rect
			(at -0.2667 0)
			(size 0.3048 0.381)
			(layers "F.Cu" "F.Mask" "F.Paste")
			(net "P3E_CPU1_P4_TX_C_DP<0>")
		)
		(pad "2" smd rect
			(at 0.2667 0)
			(size 0.3048 0.381)
			(layers "F.Cu" "F.Mask" "F.Paste")
			(net "P3E_CPU1_P4_TX_DP<0>")
		)
	)
	(footprint ""
		(layer "F.Cu")
		(at 48.82134 -346.87129 -90)
		(property "Reference" "PC441_2"
			(at 0 0 270)
			(layer "F.SilkS")
			(hide yes)
			(effects
				(font
					(size 1.27 1.27)
				)
			)
		)
		(property "Value" ""
			(at 0 0 270)
			(layer "F.Fab")
			(effects
				(font
					(size 1.27 1.27)
				)
			)
		)
		(duplicate_pad_numbers_are_jumpers no)
		(fp_line
			(start -0.7874 0.4064)
			(end -0.7874 -0.4064)
			(stroke
				(width 0.1524)
				(type default)
			)
			(layer "F.SilkS")
		)
		(fp_line
			(start 0.7874 0.4064)
			(end -0.7874 0.4064)
			(stroke
				(width 0.1524)
				(type default)
			)
			(layer "F.SilkS")
		)
		(fp_line
			(start -0.7874 -0.4064)
			(end 0.7874 -0.4064)
			(stroke
				(width 0.1524)
				(type default)
			)
			(layer "F.SilkS")
		)
		(fp_line
			(start 0.7874 -0.4064)
			(end 0.7874 0.4064)
			(stroke
				(width 0.1524)
				(type default)
			)
			(layer "F.SilkS")
		)
		(fp_line
			(start -0.67945 0.3048)
			(end -0.67945 -0.305054)
			(stroke
				(width 0.1)
				(type default)
			)
			(layer "F.Fab")
		)
		(fp_line
			(start -0.12065 0.3048)
			(end -0.67945 0.3048)
			(stroke
				(width 0.1)
				(type default)
			)
			(layer "F.Fab")
		)
		(fp_line
			(start 0.120396 0.3048)
			(end 0.120396 0.2794)
			(stroke
				(width 0.1)
				(type default)
			)
			(layer "F.Fab")
		)
		(fp_line
			(start 0.67945 0.3048)
			(end 0.120396 0.3048)
			(stroke
				(width 0.1)
				(type default)
			)
			(layer "F.Fab")
		)
		(fp_line
			(start -0.12065 0.2794)
			(end -0.12065 0.3048)
			(stroke
				(width 0.1)
				(type default)
			)
			(layer "F.Fab")
		)
		(fp_line
			(start 0.120396 0.2794)
			(end -0.12065 0.2794)
			(stroke
				(width 0.1)
				(type default)
			)
			(layer "F.Fab")
		)
		(fp_line
			(start -0.12065 -0.2794)
			(end 0.12065 -0.2794)
			(stroke
				(width 0.1)
				(type default)
			)
			(layer "F.Fab")
		)
		(fp_line
			(start 0.12065 -0.2794)
			(end 0.12065 -0.3048)
			(stroke
				(width 0.1)
				(type default)
			)
			(layer "F.Fab")
		)
		(fp_line
			(start 0.12065 -0.3048)
			(end 0.67945 -0.3048)
			(stroke
				(width 0.1)
				(type default)
			)
			(layer "F.Fab")
		)
		(fp_line
			(start 0.67945 -0.3048)
			(end 0.67945 0.3048)
			(stroke
				(width 0.1)
				(type default)
			)
			(layer "F.Fab")
		)
		(fp_line
			(start -0.67945 -0.305054)
			(end -0.12065 -0.305054)
			(stroke
				(width 0.1)
				(type default)
			)
			(layer "F.Fab")
		)
		(fp_line
			(start -0.12065 -0.305054)
			(end -0.12065 -0.2794)
			(stroke
				(width 0.1)
				(type default)
			)
			(layer "F.Fab")
		)
		(pad "1" smd circle
			(at -0.40005 0 270)
			(size 0 0)
			(layers "F.Cu" "F.Mask" "F.Paste")
			(net "SW_P12V_AUX_PVDDIO_P1_FLT")
		)
		(pad "2" smd circle
			(at 0.40005 0 270)
			(size 0 0)
			(layers "F.Cu" "F.Mask" "F.Paste")
			(net "GND")
		)
	)
)
